# T6G (Grand Teton) — schematic netlist excerpt (pin names and nets, part order shuffled) for the footprints in the layout excerpt that follows; sources: Cadence DE-HDL packaged netlist, KiCad conversion of 04192023_DAF0TMB3IC0_F0TG_MB_C_brd_V02_OCP.brd

J30  SCONN288_DDR506112002KQ  IO  pkg DDR288S_1-1VXC  page 101
  VIN_BULK0  = P12V_MEM_CPU1
  RFU0  = NC
  VIN_MGMT  = P3V3_AUX
  HSCL  = I3C_SPD_DDRD_CPU1_SCL
  HSDA  = I3C_SPD_DDRD_CPU1_SDA
  VSS0  = GND
  DQ0_A  = M_D_CPU1_SA_DQ<0>
  VSS1  = GND
  DQ1_A  = M_D_CPU1_SA_DQ<1>
  VSS2  = GND
  DQS0_A_T  = M_D_CPU1_SA_DQS_DP<0>
  DQS0_A_C  = M_D_CPU1_SA_DQS_DN<0>
  VSS3  = GND
  DQ4_A  = M_D_CPU1_SA_DQ<4>
  VSS4  = GND
  DQ5_A  = M_D_CPU1_SA_DQ<5>
  VSS5  = GND
  DQ8_A  = M_D_CPU1_SA_DQ<8>
  VSS6  = GND
  DQ9_A  = M_D_CPU1_SA_DQ<9>
  VSS7  = GND
  DQS1_A_T  = M_D_CPU1_SA_DQS_DP<1>
  DQS1_A_C  = M_D_CPU1_SA_DQS_DN<1>
  VSS8  = GND
  DQ12_A  = M_D_CPU1_SA_DQ<12>
  VSS9  = GND
  DQ13_A  = M_D_CPU1_SA_DQ<13>
  VSS10  = GND
  DQ16_A  = M_D_CPU1_SA_DQ<16>
  VSS11  = GND
  DQ17_A  = M_D_CPU1_SA_DQ<17>
  VSS12  = GND
  DQS2_A_T  = M_D_CPU1_SA_DQS_DP<2>
  DQS2_A_C  = M_D_CPU1_SA_DQS_DN<2>
  VSS13  = GND
  DQ20_A  = M_D_CPU1_SA_DQ<20>
  VSS14  = GND
  DQ21_A  = M_D_CPU1_SA_DQ<21>
  VSS15  = GND
  DQ24_A  = M_D_CPU1_SA_DQ<24>
  VSS16  = GND
  DQ25_A  = M_D_CPU1_SA_DQ<25>
  VSS17  = GND
  DQS3_A_T  = M_D_CPU1_SA_DQS_DP<3>
  DQS3_A_C  = M_D_CPU1_SA_DQS_DN<3>
  VSS18  = GND
  DQ28_A  = M_D_CPU1_SA_DQ<28>
  VSS19  = GND
  DQ29_A  = M_D_CPU1_SA_DQ<29>
  VSS20  = GND
  CB0_A  = M_D_CPU1_SA_CB<0>
  VSS21  = GND
  CB1_A  = M_D_CPU1_SA_CB<1>
  VSS22  = GND
  DQS4_A_T  = M_D_CPU1_SA_DQS_DP<4>
  DQS4_A_C  = M_D_CPU1_SA_DQS_DN<4>
  VSS23  = GND
  CB4_A  = M_D_CPU1_SA_CB<4>
  VSS24  = GND
  CB5_A  = M_D_CPU1_SA_CB<5>
  VSS25  = GND
  ALERT_N  = M_D_CPU1_ALERT_N
  VSS26  = GND
  CS0_A_N  = M_D_CPU1_SA_CS_N<0>
  VSS27  = GND
  CA0_A  = M_D_CPU1_SA_CA<0>
  VSS28  = GND
  CA2_A  = M_D_CPU1_SA_CA<2>
  VSS29  = GND
  CA4_A  = M_D_CPU1_SA_CA<4>
  VSS30  = GND
  CA6_A  = M_D_CPU1_SA_CA<6>
  VSS31  = GND
  PAR_A  = M_D_CPU1_SA_PAR
  VSS32  = GND
  CA0_B  = M_D_CPU1_SB_CA<0>
  VSS33  = GND
  CA2_B  = M_D_CPU1_SB_CA<2>
  VSS34  = GND
  CA4_B  = M_D_CPU1_SB_CA<4>
  VSS35  = GND
  CA6_B  = M_D_CPU1_SB_CA<6>
  VSS36  = GND
  CS0_B_N  = M_D_CPU1_SB_CS_N<0>
  VSS37  = GND
  \lbd||rsp_a_n\  = M_D_CPU1_SA_RSP<0>
  \lbs||rsp_b_n\  = M_D_CPU1_SB_RSP<0>
  VSS38  = GND
  CB4_B  = M_D_CPU1_SB_CB<4>
  VSS39  = GND
  CB5_B  = M_D_CPU1_SB_CB<5>
  VSS40  = GND
  \dqs9_b_t||tdqs9_b_t||dbi4_b_n\  = M_D_CPU1_SB_DQS_DP<9>
  \dqs9_b_c||tdqs9_b_c\  = M_D_CPU1_SB_DQS_DN<9>
  VSS41  = GND
  CB0_B  = M_D_CPU1_SB_CB<0>
  VSS42  = GND
  CB1_B  = M_D_CPU1_SB_CB<1>
  VSS43  = GND
  DQ0_B  = M_D_CPU1_SB_DQ<0>
  VSS44  = GND
  DQ1_B  = M_D_CPU1_SB_DQ<1>
  VSS45  = GND
  DQS0_B_T  = M_D_CPU1_SB_DQS_DP<0>
  DQS0_B_C  = M_D_CPU1_SB_DQS_DN<0>
  VSS46  = GND
  DQ4_B  = M_D_CPU1_SB_DQ<4>
  VSS47  = GND
  DQ5_B  = M_D_CPU1_SB_DQ<5>
  VSS48  = GND
  DQ8_B  = M_D_CPU1_SB_DQ<8>
  VSS49  = GND
  DQ9_B  = M_D_CPU1_SB_DQ<9>
  VSS50  = GND
  DQS1_B_T  = M_D_CPU1_SB_DQS_DP<1>
  DQS1_B_C  = M_D_CPU1_SB_DQS_DN<1>
  VSS51  = GND
  DQ12_B  = M_D_CPU1_SB_DQ<12>
  VSS52  = GND
  DQ13_B  = M_D_CPU1_SB_DQ<13>
  VSS53  = GND
  DQ16_B  = M_D_CPU1_SB_DQ<16>
  VSS54  = GND
  DQ17_B  = M_D_CPU1_SB_DQ<17>
  VSS55  = GND
  DQS2_B_T  = M_D_CPU1_SB_DQS_DP<2>
  DQS2_B_C  = M_D_CPU1_SB_DQS_DN<2>
  VSS56  = GND
  DQ20_B  = M_D_CPU1_SB_DQ<20>
  VSS57  = GND
  DQ21_B  = M_D_CPU1_SB_DQ<21>
  VSS58  = GND
  DQ24_B  = M_D_CPU1_SB_DQ<24>
  VSS59  = GND
  DQ25_B  = M_D_CPU1_SB_DQ<25>
  VSS60  = GND
  DQS3_B_T  = M_D_CPU1_SB_DQS_DP<3>
  DQS3_B_C  = M_D_CPU1_SB_DQS_DN<3>
  VSS61  = GND
  DQ28_B  = M_D_CPU1_SB_DQ<28>
  VSS62  = GND
  DQ29_B  = M_D_CPU1_SB_DQ<29>
  VSS63  = GND
  RFU1  = NC
  VIN_BULK1  = P12V_MEM_CPU1
  VIN_BULK2  = P12V_MEM_CPU1
  \pwr_good||fail_n\  = PWRGD_CHD_CPU1_DIMM
  HAS  = PD_CHD_CPU1_DIMM_SAA
  RFU2  = NC
  RFU3  = NC
  VSS64  = GND
  DQ2_A  = M_D_CPU1_SA_DQ<2>
  VSS65  = GND
  DQ3_A  = M_D_CPU1_SA_DQ<3>
  VSS66  = GND
  \dqs5_a_c||tdqs5_a_c||dqs5_a_t||tdqs5_a_t\  = M_D_CPU1_SA_DQS_DN<5>
  \dqs5_a_t||tdqs5_a_t\  = M_D_CPU1_SA_DQS_DP<5>
  VSS67  = GND
  DQ6_A  = M_D_CPU1_SA_DQ<6>
  VSS68  = GND
  DQ7_A  = M_D_CPU1_SA_DQ<7>
  VSS69  = GND
  DQ10_A  = M_D_CPU1_SA_DQ<10>
  VSS70  = GND
  DQ11_A  = M_D_CPU1_SA_DQ<11>
  VSS71  = GND
  \dqs6_a_c||tdqs6_a_c||dqs6_a_t||tdqs6_a_t\  = M_D_CPU1_SA_DQS_DN<6>
  \dqs6_a_t||tdqs6_a_t\  = M_D_CPU1_SA_DQS_DP<6>
  VSS72  = GND
  DQ14_A  = M_D_CPU1_SA_DQ<14>
  VSS73  = GND
  DQ15_A  = M_D_CPU1_SA_DQ<15>
  VSS74  = GND
  DQ18_A  = M_D_CPU1_SA_DQ<18>
  VSS75  = GND
  DQ19_A  = M_D_CPU1_SA_DQ<19>
  VSS76  = GND
  \dqs7_a_c||tdqs7_a_c\  = M_D_CPU1_SA_DQS_DN<7>
  \dqs7_a_t||tdqs7_a_t\  = M_D_CPU1_SA_DQS_DP<7>
  VSS77  = GND
  DQ22_A  = M_D_CPU1_SA_DQ<22>
  VSS78  = GND
  DQ23_A  = M_D_CPU1_SA_DQ<23>
  VSS79  = GND
  DQ26_A  = M_D_CPU1_SA_DQ<26>
  VSS80  = GND
  DQ27_A  = M_D_CPU1_SA_DQ<27>
  VSS81  = GND
  \dqs8_a_c||tdqs8_a_c\  = M_D_CPU1_SA_DQS_DN<8>
  \dqs8_a_t||tdqs8_a_t\  = M_D_CPU1_SA_DQS_DP<8>
  VSS82  = GND
  DQ30_A  = M_D_CPU1_SA_DQ<30>
  VSS83  = GND
  DQ31_A  = M_D_CPU1_SA_DQ<31>
  VSS84  = GND
  CB2_A  = M_D_CPU1_SA_CB<2>
  VSS85  = GND
  CB3_A  = M_D_CPU1_SA_CB<3>
  VSS86  = GND
  \dqs9_a_c||tdqs9_a_c\  = M_D_CPU1_SA_DQS_DN<9>
  \dqs9_a_t||tdqs9_a_t\  = M_D_CPU1_SA_DQS_DP<9>
  VSS87  = GND
  CB6_A  = M_D_CPU1_SA_CB<6>
  VSS88  = GND
  CB7_A  = M_D_CPU1_SA_CB<7>
  VSS89  = GND
  RESET_N  = M_D_CPU1_RESET_N
  VSS90  = GND
  CS1_A_N  = M_D_CPU1_SA_CS_N<1>
  VSS91  = GND
  CA1_A  = M_D_CPU1_SA_CA<1>
  VSS92  = GND
  CA3_A  = M_D_CPU1_SA_CA<3>
  VSS93  = GND
  CA5_A  = M_D_CPU1_SA_CA<5>
  VSS94  = GND
  CK_T  = M_D_CPU1_CLK_DP<0>
  CK_C  = M_D_CPU1_CLK_DN<0>
  VSS95  = GND
  RFU4  = NC
  CA1_B  = M_D_CPU1_SB_CA<1>
  VSS96  = GND
  CA3_B  = M_D_CPU1_SB_CA<3>
  VSS97  = GND
  CA5_B  = M_D_CPU1_SB_CA<5>
  VSS98  = GND
  PAR_B  = M_D_CPU1_SB_PAR
  VSS99  = GND
  CS1_B_N  = M_D_CPU1_SB_CS_N<1>
  VSS100  = GND
  RFU5  = NC
  RFU6  = NC
  VSS101  = GND
  CB6_B  = M_D_CPU1_SB_CB<6>
  VSS102  = GND
  CB7_B  = M_D_CPU1_SB_CB<7>
  VSS103  = GND
  DQS4_B_C  = M_D_CPU1_SB_DQS_DN<4>
  DQS4_B_T  = M_D_CPU1_SB_DQS_DP<4>
  VSS104  = GND
  CB2_B  = M_D_CPU1_SB_CB<2>
  VSS105  = GND
  CB3_B  = M_D_CPU1_SB_CB<3>
  VSS106  = GND
  DQ2_B  = M_D_CPU1_SB_DQ<2>
  VSS107  = GND
  DQ3_B  = M_D_CPU1_SB_DQ<3>
  VSS108  = GND
  \dqs5_b_c||tdqs5_b_c\  = M_D_CPU1_SB_DQS_DN<5>
  \dqs5_b_t||tdqs5_b_t\  = M_D_CPU1_SB_DQS_DP<5>
  VSS109  = GND
  DQ6_B  = M_D_CPU1_SB_DQ<6>
  VSS110  = GND
  DQ7_B  = M_D_CPU1_SB_DQ<7>
  VSS111  = GND
  DQ10_B  = M_D_CPU1_SB_DQ<10>
  VSS112  = GND
  DQ11_B  = M_D_CPU1_SB_DQ<11>
  VSS113  = GND
  \dqs6_b_c||tdqs6_b_c\  = M_D_CPU1_SB_DQS_DN<6>
  \dqs6_b_t||tdqs6_b_t\  = M_D_CPU1_SB_DQS_DP<6>
  VSS114  = GND
  DQ14_B  = M_D_CPU1_SB_DQ<14>
  VSS115  = GND
  DQ15_B  = M_D_CPU1_SB_DQ<15>
  VSS116  = GND
  DQ18_B  = M_D_CPU1_SB_DQ<18>
  VSS117  = GND
  DQ19_B  = M_D_CPU1_SB_DQ<19>
  VSS118  = GND
  \dqs7_b_c||tdqs7_b_c\  = M_D_CPU1_SB_DQS_DN<7>
  \dqs7_b_t||tdqs7_b_t\  = M_D_CPU1_SB_DQS_DP<7>
  VSS119  = GND
  DQ22_B  = M_D_CPU1_SB_DQ<22>
  VSS120  = GND
  DQ23_B  = M_D_CPU1_SB_DQ<23>
  VSS121  = GND
  DQ26_B  = M_D_CPU1_SB_DQ<26>
  VSS122  = GND
  DQ27_B  = M_D_CPU1_SB_DQ<27>
  VSS123  = GND
  \dqs8_b_c||tdqs8_b_c\  = M_D_CPU1_SB_DQS_DN<8>
  \dqs8_b_t||tdqs8_b_t\  = M_D_CPU1_SB_DQS_DP<8>
  VSS124  = GND
  DQ30_B  = M_D_CPU1_SB_DQ<30>
  VSS125  = GND
  DQ31_B  = M_D_CPU1_SB_DQ<31>
  VSS126  = GND
  G1  = GND
  G2  = GND
  G3  = GND

(kicad_pcb
	(version 20260206)
	(generator "pcbnew")
	(generator_version "10.0")
	(general
		(thickness 1.6)
		(legacy_teardrops no)
	)
	(paper "A4")
	(title_block
		(title "04192023_DAF0TMB3IC0_F0TG_MB_C_brd_V02_OCP.brd")
		(comment 1 "Grand Teton / footprint 3579 of 8354 (J30), pads 185-230 of 291")
	)
	(layers
		(0 "F.Cu" signal "TOP")
		(4 "In1.Cu" signal "GND")
		(6 "In2.Cu" signal "IN1")
		(8 "In3.Cu" signal "GND1")
		(10 "In4.Cu" signal "IN2")
		(12 "In5.Cu" signal "GND2")
		(14 "In6.Cu" signal "IN3")
		(16 "In7.Cu" signal "GND3")
		(18 "In8.Cu" signal "VCC")
		(20 "In9.Cu" signal "VCC1")
		(22 "In10.Cu" signal "GND4")
		(24 "In11.Cu" signal "IN4")
		(26 "In12.Cu" signal "GND5")
		(28 "In13.Cu" signal "IN5")
		(30 "In14.Cu" signal "GND6")
		(32 "In15.Cu" signal "IN6")
		(34 "In16.Cu" signal "GND7")
		(2 "B.Cu" signal "BOTTOM")
		(9 "F.Adhes" user "F.Adhesive")
		(11 "B.Adhes" user "B.Adhesive")
		(13 "F.Paste" user "Package Geometry/Pastemask Top")
		(15 "B.Paste" user "Package Geometry/Pastemask Bottom")
		(5 "F.SilkS" user "Ref Des/Silkscreen Top")
		(7 "B.SilkS" user "Ref Des/Silkscreen Bottom")
		(1 "F.Mask" user "Board Geometry/Soldermask Top")
		(3 "B.Mask" user "Board Geometry/Soldermask Bottom")
		(17 "Dwgs.User" user "User.Drawings")
		(19 "Cmts.User" user "User.Comments")
		(21 "Eco1.User" user "User.Eco1")
		(23 "Eco2.User" user "User.Eco2")
		(25 "Edge.Cuts" user "Board Geometry/Outline")
		(27 "Margin" user)
		(31 "F.CrtYd" user "Package Geometry/Place Bound Top")
		(29 "B.CrtYd" user "Package Geometry/Place Bound Bottom")
		(35 "F.Fab" user "Ref Des/Assembly Top")
		(33 "B.Fab" user "Ref Des/Assembly Bottom")
	)
	(footprint ""
		(layer "F.Cu")
		(at 34.74593 -255.560322 180)
		(property "Reference" "J30"
			(at 3.12293 -81.850992 0)
			(unlocked yes)
			(layer "F.SilkS")
			(effects
				(font
					(size 0.7874 0.5842)
					(thickness 0.1524)
				)
			)
		)
		(property "Value" ""
			(at 0 0 180)
			(layer "F.Fab")
			(effects
				(font
					(size 1.27 1.27)
				)
			)
		)
		(duplicate_pad_numbers_are_jumpers no)
		(pad "185" smd rect
			(at 2.050034 -29.325062 90)
			(size 0.519938 1.4986)
			(layers "F.Cu" "F.Mask" "F.Paste")
			(net "M_D_CPU1_SA_DQ<26>")
		)
		(pad "186" smd rect
			(at 2.050034 -28.474924 90)
			(size 0.519938 1.4986)
			(layers "F.Cu" "F.Mask" "F.Paste")
			(net "GND")
		)
		(pad "187" smd rect
			(at 2.050034 -27.62504 90)
			(size 0.519938 1.4986)
			(layers "F.Cu" "F.Mask" "F.Paste")
			(net "M_D_CPU1_SA_DQ<27>")
		)
		(pad "188" smd rect
			(at 2.050034 -26.774902 90)
			(size 0.519938 1.4986)
			(layers "F.Cu" "F.Mask" "F.Paste")
			(net "GND")
		)
		(pad "189" smd rect
			(at 2.050034 -25.925018 90)
			(size 0.519938 1.4986)
			(layers "F.Cu" "F.Mask" "F.Paste")
			(net "M_D_CPU1_SA_DQS_DN<8>")
		)
		(pad "190" smd rect
			(at 2.050034 -25.07488 90)
			(size 0.519938 1.4986)
			(layers "F.Cu" "F.Mask" "F.Paste")
			(net "M_D_CPU1_SA_DQS_DP<8>")
		)
		(pad "191" smd rect
			(at 2.050034 -24.224996 90)
			(size 0.519938 1.4986)
			(layers "F.Cu" "F.Mask" "F.Paste")
			(net "GND")
		)
		(pad "192" smd rect
			(at 2.050034 -23.375112 90)
			(size 0.519938 1.4986)
			(layers "F.Cu" "F.Mask" "F.Paste")
			(net "M_D_CPU1_SA_DQ<30>")
		)
		(pad "193" smd rect
			(at 2.050034 -22.524974 90)
			(size 0.519938 1.4986)
			(layers "F.Cu" "F.Mask" "F.Paste")
			(net "GND")
		)
		(pad "194" smd rect
			(at 2.050034 -21.67509 90)
			(size 0.519938 1.4986)
			(layers "F.Cu" "F.Mask" "F.Paste")
			(net "M_D_CPU1_SA_DQ<31>")
		)
		(pad "195" smd rect
			(at 2.050034 -20.824952 90)
			(size 0.519938 1.4986)
			(layers "F.Cu" "F.Mask" "F.Paste")
			(net "GND")
		)
		(pad "196" smd rect
			(at 2.050034 -19.975068 90)
			(size 0.519938 1.4986)
			(layers "F.Cu" "F.Mask" "F.Paste")
			(net "M_D_CPU1_SA_CB<2>")
		)
		(pad "197" smd rect
			(at 2.050034 -19.12493 90)
			(size 0.519938 1.4986)
			(layers "F.Cu" "F.Mask" "F.Paste")
			(net "GND")
		)
		(pad "198" smd rect
			(at 2.050034 -18.275046 90)
			(size 0.519938 1.4986)
			(layers "F.Cu" "F.Mask" "F.Paste")
			(net "M_D_CPU1_SA_CB<3>")
		)
		(pad "199" smd rect
			(at 2.050034 -17.424908 90)
			(size 0.519938 1.4986)
			(layers "F.Cu" "F.Mask" "F.Paste")
			(net "GND")
		)
		(pad "200" smd rect
			(at 2.050034 -16.575024 90)
			(size 0.519938 1.4986)
			(layers "F.Cu" "F.Mask" "F.Paste")
			(net "M_D_CPU1_SA_DQS_DN<9>")
		)
		(pad "201" smd rect
			(at 2.050034 -15.724886 90)
			(size 0.519938 1.4986)
			(layers "F.Cu" "F.Mask" "F.Paste")
			(net "M_D_CPU1_SA_DQS_DP<9>")
		)
		(pad "202" smd rect
			(at 2.050034 -14.875002 90)
			(size 0.519938 1.4986)
			(layers "F.Cu" "F.Mask" "F.Paste")
			(net "GND")
		)
		(pad "203" smd rect
			(at 2.050034 -14.025118 90)
			(size 0.519938 1.4986)
			(layers "F.Cu" "F.Mask" "F.Paste")
			(net "M_D_CPU1_SA_CB<6>")
		)
		(pad "204" smd rect
			(at 2.050034 -13.17498 90)
			(size 0.519938 1.4986)
			(layers "F.Cu" "F.Mask" "F.Paste")
			(net "GND")
		)
		(pad "205" smd rect
			(at 2.050034 -12.325096 90)
			(size 0.519938 1.4986)
			(layers "F.Cu" "F.Mask" "F.Paste")
			(net "M_D_CPU1_SA_CB<7>")
		)
		(pad "206" smd rect
			(at 2.050034 -11.474958 90)
			(size 0.519938 1.4986)
			(layers "F.Cu" "F.Mask" "F.Paste")
			(net "GND")
		)
		(pad "207" smd rect
			(at 2.050034 -10.625074 90)
			(size 0.519938 1.4986)
			(layers "F.Cu" "F.Mask" "F.Paste")
			(net "M_D_CPU1_RESET_N")
		)
		(pad "208" smd rect
			(at 2.050034 -9.774936 90)
			(size 0.519938 1.4986)
			(layers "F.Cu" "F.Mask" "F.Paste")
			(net "GND")
		)
		(pad "209" smd rect
			(at 2.050034 -8.925052 90)
			(size 0.519938 1.4986)
			(layers "F.Cu" "F.Mask" "F.Paste")
			(net "M_D_CPU1_SA_CS_N<1>")
		)
		(pad "210" smd rect
			(at 2.050034 -8.074914 90)
			(size 0.519938 1.4986)
			(layers "F.Cu" "F.Mask" "F.Paste")
			(net "GND")
		)
		(pad "211" smd rect
			(at 2.050034 -7.22503 90)
			(size 0.519938 1.4986)
			(layers "F.Cu" "F.Mask" "F.Paste")
			(net "M_D_CPU1_SA_CA<1>")
		)
		(pad "212" smd rect
			(at 2.050034 -6.374892 90)
			(size 0.519938 1.4986)
			(layers "F.Cu" "F.Mask" "F.Paste")
			(net "GND")
		)
		(pad "213" smd rect
			(at 2.050034 -5.525008 90)
			(size 0.519938 1.4986)
			(layers "F.Cu" "F.Mask" "F.Paste")
			(net "M_D_CPU1_SA_CA<3>")
		)
		(pad "214" smd rect
			(at 2.050034 -4.675124 90)
			(size 0.519938 1.4986)
			(layers "F.Cu" "F.Mask" "F.Paste")
			(net "GND")
		)
		(pad "215" smd rect
			(at 2.050034 -3.824986 90)
			(size 0.519938 1.4986)
			(layers "F.Cu" "F.Mask" "F.Paste")
			(net "M_D_CPU1_SA_CA<5>")
		)
		(pad "216" smd rect
			(at 2.050034 -2.975102 90)
			(size 0.519938 1.4986)
			(layers "F.Cu" "F.Mask" "F.Paste")
			(net "GND")
		)
		(pad "217" smd rect
			(at 2.050034 -2.124964 90)
			(size 0.519938 1.4986)
			(layers "F.Cu" "F.Mask" "F.Paste")
			(net "M_D_CPU1_CLK_DP<0>")
		)
		(pad "218" smd rect
			(at 2.050034 -1.27508 90)
			(size 0.519938 1.4986)
			(layers "F.Cu" "F.Mask" "F.Paste")
			(net "M_D_CPU1_CLK_DN<0>")
		)
		(pad "219" smd rect
			(at 2.050034 -0.424942 90)
			(size 0.519938 1.4986)
			(layers "F.Cu" "F.Mask" "F.Paste")
			(net "GND")
		)
		(pad "220" smd rect
			(at 2.050034 5.525008 90)
			(size 0.519938 1.4986)
			(layers "F.Cu" "F.Mask" "F.Paste")
			(net "Net_2302")
		)
		(pad "221" smd rect
			(at 2.050034 6.374892 90)
			(size 0.519938 1.4986)
			(layers "F.Cu" "F.Mask" "F.Paste")
			(net "M_D_CPU1_SB_CA<1>")
		)
		(pad "222" smd rect
			(at 2.050034 7.22503 90)
			(size 0.519938 1.4986)
			(layers "F.Cu" "F.Mask" "F.Paste")
			(net "GND")
		)
		(pad "223" smd rect
			(at 2.050034 8.074914 90)
			(size 0.519938 1.4986)
			(layers "F.Cu" "F.Mask" "F.Paste")
			(net "M_D_CPU1_SB_CA<3>")
		)
		(pad "224" smd rect
			(at 2.050034 8.925052 90)
			(size 0.519938 1.4986)
			(layers "F.Cu" "F.Mask" "F.Paste")
			(net "GND")
		)
		(pad "225" smd rect
			(at 2.050034 9.774936 90)
			(size 0.519938 1.4986)
			(layers "F.Cu" "F.Mask" "F.Paste")
			(net "M_D_CPU1_SB_CA<5>")
		)
		(pad "226" smd rect
			(at 2.050034 10.625074 90)
			(size 0.519938 1.4986)
			(layers "F.Cu" "F.Mask" "F.Paste")
			(net "GND")
		)
		(pad "227" smd rect
			(at 2.050034 11.474958 90)
			(size 0.519938 1.4986)
			(layers "F.Cu" "F.Mask" "F.Paste")
			(net "M_D_CPU1_SB_PAR")
		)
		(pad "228" smd rect
			(at 2.050034 12.325096 90)
			(size 0.519938 1.4986)
			(layers "F.Cu" "F.Mask" "F.Paste")
			(net "GND")
		)
		(pad "229" smd rect
			(at 2.050034 13.17498 90)
			(size 0.519938 1.4986)
			(layers "F.Cu" "F.Mask" "F.Paste")
			(net "M_D_CPU1_SB_CS_N<1>")
		)
		(pad "230" smd rect
			(at 2.050034 14.025118 90)
			(size 0.519938 1.4986)
			(layers "F.Cu" "F.Mask" "F.Paste")
			(net "GND")
		)
	)
)
